(kicad_pcb
	(version 20260206)
	(generator "pcbnew")
	(generator_version "10.0")
	(general
		(thickness 1.6)
		(legacy_teardrops no)
	)
	(paper "A4")
	(title_block
		(title "03242023_DA0F0TMBIJ0_F0T_Motherboard_J_brd_V01_OCP.brd")
		(comment 1 "Grand Teton / footprints 2848-2854 of 6105")
	)
	(layers
		(0 "F.Cu" signal "TOP")
		(4 "In1.Cu" signal "GND")
		(6 "In2.Cu" signal "IN1")
		(8 "In3.Cu" signal "GND1")
		(10 "In4.Cu" signal "IN2")
		(12 "In5.Cu" signal "GND2")
		(14 "In6.Cu" signal "IN3")
		(16 "In7.Cu" signal "GND3")
		(18 "In8.Cu" signal "VCC")
		(20 "In9.Cu" signal "VCC1")
		(22 "In10.Cu" signal "GND4")
		(24 "In11.Cu" signal "IN4")
		(26 "In12.Cu" signal "GND5")
		(28 "In13.Cu" signal "IN5")
		(30 "In14.Cu" signal "GND6")
		(32 "In15.Cu" signal "IN6")
		(34 "In16.Cu" signal "GND7")
		(2 "B.Cu" signal "BOTTOM")
		(9 "F.Adhes" user "F.Adhesive")
		(11 "B.Adhes" user "B.Adhesive")
		(13 "F.Paste" user "Package Geometry/Pastemask Top")
		(15 "B.Paste" user "Package Geometry/Pastemask Bottom")
		(5 "F.SilkS" user "Ref Des/Silkscreen Top")
		(7 "B.SilkS" user "Ref Des/Silkscreen Bottom")
		(1 "F.Mask" user "Board Geometry/Soldermask Top")
		(3 "B.Mask" user "Board Geometry/Soldermask Bottom")
		(17 "Dwgs.User" user "User.Drawings")
		(19 "Cmts.User" user "User.Comments")
		(21 "Eco1.User" user "User.Eco1")
		(23 "Eco2.User" user "User.Eco2")
		(25 "Edge.Cuts" user "Board Geometry/Outline")
		(27 "Margin" user)
		(31 "F.CrtYd" user "Package Geometry/Place Bound Top")
		(29 "B.CrtYd" user "Package Geometry/Place Bound Bottom")
		(35 "F.Fab" user "Ref Des/Assembly Top")
		(33 "B.Fab" user "Ref Des/Assembly Bottom")
	)
	(footprint ""
		(layer "F.Cu")
		(at 389.636 -31.841948 180)
		(property "Reference" "R4614"
			(at 0 0 180)
			(layer "F.SilkS")
			(hide yes)
			(effects
				(font
					(size 1.27 1.27)
				)
			)
		)
		(property "Value" ""
			(at 0 0 180)
			(layer "F.Fab")
			(effects
				(font
					(size 1.27 1.27)
				)
			)
		)
		(duplicate_pad_numbers_are_jumpers no)
		(fp_line
			(start 0.7874 0.4064)
			(end -0.7874 0.4064)
			(stroke
				(width 0.1524)
				(type default)
			)
			(layer "F.SilkS")
		)
		(fp_line
			(start 0.7874 -0.4064)
			(end 0.7874 0.4064)
			(stroke
				(width 0.1524)
				(type default)
			)
			(layer "F.SilkS")
		)
		(fp_line
			(start -0.7874 0.4064)
			(end -0.7874 -0.4064)
			(stroke
				(width 0.1524)
				(type default)
			)
			(layer "F.SilkS")
		)
		(fp_line
			(start -0.7874 -0.4064)
			(end 0.7874 -0.4064)
			(stroke
				(width 0.1524)
				(type default)
			)
			(layer "F.SilkS")
		)
		(fp_line
			(start 0.67945 0.3048)
			(end 0.120396 0.3048)
			(stroke
				(width 0.1)
				(type default)
			)
			(layer "F.Fab")
		)
		(fp_line
			(start 0.67945 -0.3048)
			(end 0.67945 0.3048)
			(stroke
				(width 0.1)
				(type default)
			)
			(layer "F.Fab")
		)
		(fp_line
			(start 0.12065 -0.2794)
			(end 0.12065 -0.3048)
			(stroke
				(width 0.1)
				(type default)
			)
			(layer "F.Fab")
		)
		(fp_line
			(start 0.12065 -0.3048)
			(end 0.67945 -0.3048)
			(stroke
				(width 0.1)
				(type default)
			)
			(layer "F.Fab")
		)
		(fp_line
			(start 0.120396 0.3048)
			(end 0.120396 0.2794)
			(stroke
				(width 0.1)
				(type default)
			)
			(layer "F.Fab")
		)
		(fp_line
			(start 0.120396 0.2794)
			(end -0.12065 0.2794)
			(stroke
				(width 0.1)
				(type default)
			)
			(layer "F.Fab")
		)
		(fp_line
			(start -0.12065 0.3048)
			(end -0.67945 0.3048)
			(stroke
				(width 0.1)
				(type default)
			)
			(layer "F.Fab")
		)
		(fp_line
			(start -0.12065 0.2794)
			(end -0.12065 0.3048)
			(stroke
				(width 0.1)
				(type default)
			)
			(layer "F.Fab")
		)
		(fp_line
			(start -0.12065 -0.2794)
			(end 0.12065 -0.2794)
			(stroke
				(width 0.1)
				(type default)
			)
			(layer "F.Fab")
		)
		(fp_line
			(start -0.12065 -0.305054)
			(end -0.12065 -0.2794)
			(stroke
				(width 0.1)
				(type default)
			)
			(layer "F.Fab")
		)
		(fp_line
			(start -0.67945 0.3048)
			(end -0.67945 -0.305054)
			(stroke
				(width 0.1)
				(type default)
			)
			(layer "F.Fab")
		)
		(fp_line
			(start -0.67945 -0.305054)
			(end -0.12065 -0.305054)
			(stroke
				(width 0.1)
				(type default)
			)
			(layer "F.Fab")
		)
		(pad "1" smd circle
			(at -0.40005 0 180)
			(size 0 0)
			(layers "F.Cu" "F.Mask" "F.Paste")
			(net "HP_OCP_V3_1_RST")
		)
		(pad "2" smd circle
			(at 0.40005 0 180)
			(size 0 0)
			(layers "F.Cu" "F.Mask" "F.Paste")
			(net "HP_OCP_V3_1_RST_R")
		)
	)
	(footprint ""
		(layer "F.Cu")
		(at 102.844346 -358.452674 180)
		(property "Reference" "C2447"
			(at 0 0 180)
			(layer "F.SilkS")
			(hide yes)
			(effects
				(font
					(size 1.27 1.27)
				)
			)
		)
		(property "Value" ""
			(at 0 0 180)
			(layer "F.Fab")
			(effects
				(font
					(size 1.27 1.27)
				)
			)
		)
		(duplicate_pad_numbers_are_jumpers no)
		(fp_line
			(start 0.7874 0.4064)
			(end -0.7874 0.4064)
			(stroke
				(width 0.1524)
				(type default)
			)
			(layer "F.SilkS")
		)
		(fp_line
			(start 0.7874 -0.4064)
			(end 0.7874 0.4064)
			(stroke
				(width 0.1524)
				(type default)
			)
			(layer "F.SilkS")
		)
		(fp_line
			(start -0.7874 0.4064)
			(end -0.7874 -0.4064)
			(stroke
				(width 0.1524)
				(type default)
			)
			(layer "F.SilkS")
		)
		(fp_line
			(start -0.7874 -0.4064)
			(end 0.7874 -0.4064)
			(stroke
				(width 0.1524)
				(type default)
			)
			(layer "F.SilkS")
		)
		(fp_line
			(start 0.67945 0.3048)
			(end 0.120396 0.3048)
			(stroke
				(width 0.1)
				(type default)
			)
			(layer "F.Fab")
		)
		(fp_line
			(start 0.67945 -0.3048)
			(end 0.67945 0.3048)
			(stroke
				(width 0.1)
				(type default)
			)
			(layer "F.Fab")
		)
		(fp_line
			(start 0.12065 -0.2794)
			(end 0.12065 -0.3048)
			(stroke
				(width 0.1)
				(type default)
			)
			(layer "F.Fab")
		)
		(fp_line
			(start 0.12065 -0.3048)
			(end 0.67945 -0.3048)
			(stroke
				(width 0.1)
				(type default)
			)
			(layer "F.Fab")
		)
		(fp_line
			(start 0.120396 0.3048)
			(end 0.120396 0.2794)
			(stroke
				(width 0.1)
				(type default)
			)
			(layer "F.Fab")
		)
		(fp_line
			(start 0.120396 0.2794)
			(end -0.12065 0.2794)
			(stroke
				(width 0.1)
				(type default)
			)
			(layer "F.Fab")
		)
		(fp_line
			(start -0.12065 0.3048)
			(end -0.67945 0.3048)
			(stroke
				(width 0.1)
				(type default)
			)
			(layer "F.Fab")
		)
		(fp_line
			(start -0.12065 0.2794)
			(end -0.12065 0.3048)
			(stroke
				(width 0.1)
				(type default)
			)
			(layer "F.Fab")
		)
		(fp_line
			(start -0.12065 -0.2794)
			(end 0.12065 -0.2794)
			(stroke
				(width 0.1)
				(type default)
			)
			(layer "F.Fab")
		)
		(fp_line
			(start -0.12065 -0.305054)
			(end -0.12065 -0.2794)
			(stroke
				(width 0.1)
				(type default)
			)
			(layer "F.Fab")
		)
		(fp_line
			(start -0.67945 0.3048)
			(end -0.67945 -0.305054)
			(stroke
				(width 0.1)
				(type default)
			)
			(layer "F.Fab")
		)
		(fp_line
			(start -0.67945 -0.305054)
			(end -0.12065 -0.305054)
			(stroke
				(width 0.1)
				(type default)
			)
			(layer "F.Fab")
		)
		(pad "1" smd circle
			(at -0.40005 0 180)
			(size 0 0)
			(layers "F.Cu" "F.Mask" "F.Paste")
			(net "PWRGD_PVCCFA_EHV_FIVRA_CPU1_R")
		)
		(pad "2" smd circle
			(at 0.40005 0 180)
			(size 0 0)
			(layers "F.Cu" "F.Mask" "F.Paste")
			(net "GND")
		)
	)
	(footprint ""
		(layer "F.Cu")
		(at 360.444542 -389.19277)
		(property "Reference" "R4169"
			(at 0 0 0)
			(layer "F.SilkS")
			(hide yes)
			(effects
				(font
					(size 1.27 1.27)
				)
			)
		)
		(property "Value" ""
			(at 0 0 0)
			(layer "F.Fab")
			(effects
				(font
					(size 1.27 1.27)
				)
			)
		)
		(duplicate_pad_numbers_are_jumpers no)
		(fp_line
			(start -0.7874 -0.4064)
			(end 0.7874 -0.4064)
			(stroke
				(width 0.1524)
				(type default)
			)
			(layer "F.SilkS")
		)
		(fp_line
			(start -0.7874 0.4064)
			(end -0.7874 -0.4064)
			(stroke
				(width 0.1524)
				(type default)
			)
			(layer "F.SilkS")
		)
		(fp_line
			(start 0.7874 -0.4064)
			(end 0.7874 0.4064)
			(stroke
				(width 0.1524)
				(type default)
			)
			(layer "F.SilkS")
		)
		(fp_line
			(start 0.7874 0.4064)
			(end -0.7874 0.4064)
			(stroke
				(width 0.1524)
				(type default)
			)
			(layer "F.SilkS")
		)
		(fp_line
			(start -0.67945 -0.305054)
			(end -0.12065 -0.305054)
			(stroke
				(width 0.1)
				(type default)
			)
			(layer "F.Fab")
		)
		(fp_line
			(start -0.67945 0.3048)
			(end -0.67945 -0.305054)
			(stroke
				(width 0.1)
				(type default)
			)
			(layer "F.Fab")
		)
		(fp_line
			(start -0.12065 -0.305054)
			(end -0.12065 -0.2794)
			(stroke
				(width 0.1)
				(type default)
			)
			(layer "F.Fab")
		)
		(fp_line
			(start -0.12065 -0.2794)
			(end 0.12065 -0.2794)
			(stroke
				(width 0.1)
				(type default)
			)
			(layer "F.Fab")
		)
		(fp_line
			(start -0.12065 0.2794)
			(end -0.12065 0.3048)
			(stroke
				(width 0.1)
				(type default)
			)
			(layer "F.Fab")
		)
		(fp_line
			(start -0.12065 0.3048)
			(end -0.67945 0.3048)
			(stroke
				(width 0.1)
				(type default)
			)
			(layer "F.Fab")
		)
		(fp_line
			(start 0.120396 0.2794)
			(end -0.12065 0.2794)
			(stroke
				(width 0.1)
				(type default)
			)
			(layer "F.Fab")
		)
		(fp_line
			(start 0.120396 0.3048)
			(end 0.120396 0.2794)
			(stroke
				(width 0.1)
				(type default)
			)
			(layer "F.Fab")
		)
		(fp_line
			(start 0.12065 -0.3048)
			(end 0.67945 -0.3048)
			(stroke
				(width 0.1)
				(type default)
			)
			(layer "F.Fab")
		)
		(fp_line
			(start 0.12065 -0.2794)
			(end 0.12065 -0.3048)
			(stroke
				(width 0.1)
				(type default)
			)
			(layer "F.Fab")
		)
		(fp_line
			(start 0.67945 -0.3048)
			(end 0.67945 0.3048)
			(stroke
				(width 0.1)
				(type default)
			)
			(layer "F.Fab")
		)
		(fp_line
			(start 0.67945 0.3048)
			(end 0.120396 0.3048)
			(stroke
				(width 0.1)
				(type default)
			)
			(layer "F.Fab")
		)
		(pad "1" smd circle
			(at -0.40005 0)
			(size 0 0)
			(layers "F.Cu" "F.Mask" "F.Paste")
			(net "P3V3_AUX")
		)
		(pad "2" smd circle
			(at 0.40005 0)
			(size 0 0)
			(layers "F.Cu" "F.Mask" "F.Paste")
			(net "GPU_3V3IO_RSVD3_ISO")
		)
	)
	(footprint ""
		(layer "F.Cu")
		(at 390.015984 -16.088614 90)
		(property "Reference" "C839"
			(at 0 0 90)
			(layer "F.SilkS")
			(hide yes)
			(effects
				(font
					(size 1.27 1.27)
				)
			)
		)
		(property "Value" ""
			(at 0 0 90)
			(layer "F.Fab")
			(effects
				(font
					(size 1.27 1.27)
				)
			)
		)
		(duplicate_pad_numbers_are_jumpers no)
		(fp_line
			(start 0.299974 -0.150114)
			(end 0.299974 0.150114)
			(stroke
				(width 0.1)
				(type default)
			)
			(layer "F.Fab")
		)
		(fp_line
			(start -0.299974 -0.150114)
			(end 0.299974 -0.150114)
			(stroke
				(width 0.1)
				(type default)
			)
			(layer "F.Fab")
		)
		(fp_line
			(start 0.299974 0.150114)
			(end -0.299974 0.150114)
			(stroke
				(width 0.1)
				(type default)
			)
			(layer "F.Fab")
		)
		(fp_line
			(start -0.299974 0.150114)
			(end -0.299974 -0.150114)
			(stroke
				(width 0.1)
				(type default)
			)
			(layer "F.Fab")
		)
		(pad "1" smd rect
			(at -0.2667 0 90)
			(size 0.3048 0.381)
			(layers "F.Cu" "F.Mask" "F.Paste")
			(net "P5E_CPU0_PE1_TX_C_DP<15>")
		)
		(pad "2" smd rect
			(at 0.2667 0 90)
			(size 0.3048 0.381)
			(layers "F.Cu" "F.Mask" "F.Paste")
			(net "P5E_CPU0_PE1_TX_DP<15>")
		)
	)
	(footprint ""
		(layer "F.Cu")
		(at 251.16409 -48.121062 -90)
		(property "Reference" "PC2206"
			(at 0 0 270)
			(layer "F.SilkS")
			(hide yes)
			(effects
				(font
					(size 1.27 1.27)
				)
			)
		)
		(property "Value" ""
			(at 0 0 270)
			(layer "F.Fab")
			(effects
				(font
					(size 1.27 1.27)
				)
			)
		)
		(duplicate_pad_numbers_are_jumpers no)
		(fp_line
			(start -0.7874 0.4064)
			(end -0.7874 -0.4064)
			(stroke
				(width 0.1524)
				(type default)
			)
			(layer "F.SilkS")
		)
		(fp_line
			(start 0.7874 0.4064)
			(end -0.7874 0.4064)
			(stroke
				(width 0.1524)
				(type default)
			)
			(layer "F.SilkS")
		)
		(fp_line
			(start -0.7874 -0.4064)
			(end 0.7874 -0.4064)
			(stroke
				(width 0.1524)
				(type default)
			)
			(layer "F.SilkS")
		)
		(fp_line
			(start 0.7874 -0.4064)
			(end 0.7874 0.4064)
			(stroke
				(width 0.1524)
				(type default)
			)
			(layer "F.SilkS")
		)
		(fp_line
			(start -0.67945 0.3048)
			(end -0.67945 -0.305054)
			(stroke
				(width 0.1)
				(type default)
			)
			(layer "F.Fab")
		)
		(fp_line
			(start -0.12065 0.3048)
			(end -0.67945 0.3048)
			(stroke
				(width 0.1)
				(type default)
			)
			(layer "F.Fab")
		)
		(fp_line
			(start 0.120396 0.3048)
			(end 0.120396 0.2794)
			(stroke
				(width 0.1)
				(type default)
			)
			(layer "F.Fab")
		)
		(fp_line
			(start 0.67945 0.3048)
			(end 0.120396 0.3048)
			(stroke
				(width 0.1)
				(type default)
			)
			(layer "F.Fab")
		)
		(fp_line
			(start -0.12065 0.2794)
			(end -0.12065 0.3048)
			(stroke
				(width 0.1)
				(type default)
			)
			(layer "F.Fab")
		)
		(fp_line
			(start 0.120396 0.2794)
			(end -0.12065 0.2794)
			(stroke
				(width 0.1)
				(type default)
			)
			(layer "F.Fab")
		)
		(fp_line
			(start -0.12065 -0.2794)
			(end 0.12065 -0.2794)
			(stroke
				(width 0.1)
				(type default)
			)
			(layer "F.Fab")
		)
		(fp_line
			(start 0.12065 -0.2794)
			(end 0.12065 -0.3048)
			(stroke
				(width 0.1)
				(type default)
			)
			(layer "F.Fab")
		)
		(fp_line
			(start 0.12065 -0.3048)
			(end 0.67945 -0.3048)
			(stroke
				(width 0.1)
				(type default)
			)
			(layer "F.Fab")
		)
		(fp_line
			(start 0.67945 -0.3048)
			(end 0.67945 0.3048)
			(stroke
				(width 0.1)
				(type default)
			)
			(layer "F.Fab")
		)
		(fp_line
			(start -0.67945 -0.305054)
			(end -0.12065 -0.305054)
			(stroke
				(width 0.1)
				(type default)
			)
			(layer "F.Fab")
		)
		(fp_line
			(start -0.12065 -0.305054)
			(end -0.12065 -0.2794)
			(stroke
				(width 0.1)
				(type default)
			)
			(layer "F.Fab")
		)
		(pad "1" smd circle
			(at -0.40005 0 270)
			(size 0 0)
			(layers "F.Cu" "F.Mask" "F.Paste")
			(net "P12V_E1S_0")
		)
		(pad "2" smd circle
			(at 0.40005 0 270)
			(size 0 0)
			(layers "F.Cu" "F.Mask" "F.Paste")
			(net "GND")
		)
	)
	(footprint ""
		(layer "F.Cu")
		(at 456.927204 -70.255384 -90)
		(property "Reference" "PC2342"
			(at 0 0 270)
			(layer "F.SilkS")
			(hide yes)
			(effects
				(font
					(size 1.27 1.27)
				)
			)
		)
		(property "Value" ""
			(at 0 0 270)
			(layer "F.Fab")
			(effects
				(font
					(size 1.27 1.27)
				)
			)
		)
		(duplicate_pad_numbers_are_jumpers no)
		(fp_line
			(start -1.524 0.762)
			(end -1.524 -0.762)
			(stroke
				(width 0.1524)
				(type default)
			)
			(layer "F.SilkS")
		)
		(fp_line
			(start 1.524 0.762)
			(end -1.524 0.762)
			(stroke
				(width 0.1524)
				(type default)
			)
			(layer "F.SilkS")
		)
		(fp_line
			(start -1.524 -0.762)
			(end 1.524 -0.762)
			(stroke
				(width 0.1524)
				(type default)
			)
			(layer "F.SilkS")
		)
		(fp_line
			(start 1.524 -0.762)
			(end 1.524 0.762)
			(stroke
				(width 0.1524)
				(type default)
			)
			(layer "F.SilkS")
		)
		(fp_line
			(start -1.1049 0.724916)
			(end 1.1049 0.724916)
			(stroke
				(width 0.1)
				(type default)
			)
			(layer "F.Fab")
		)
		(fp_line
			(start 1.1049 0.724916)
			(end 1.1049 -0.724916)
			(stroke
				(width 0.1)
				(type default)
			)
			(layer "F.Fab")
		)
		(fp_line
			(start -1.1049 -0.724916)
			(end -1.1049 0.724916)
			(stroke
				(width 0.1)
				(type default)
			)
			(layer "F.Fab")
		)
		(fp_line
			(start 1.1049 -0.724916)
			(end -1.1049 -0.724916)
			(stroke
				(width 0.1)
				(type default)
			)
			(layer "F.Fab")
		)
		(pad "1" smd rect
			(at -0.889 0 90)
			(size 1.016 1.27)
			(layers "F.Cu" "F.Mask" "F.Paste")
			(net "SW_P3V3_AUX_FLT")
		)
		(pad "2" smd rect
			(at 0.889 0 90)
			(size 1.016 1.27)
			(layers "F.Cu" "F.Mask" "F.Paste")
			(net "GND")
		)
	)
	(footprint ""
		(layer "F.Cu")
		(at 382.168908 -75.376278 90)
		(property "Reference" "PC1235"
			(at 0 0 90)
			(layer "F.SilkS")
			(hide yes)
			(effects
				(font
					(size 1.27 1.27)
				)
			)
		)
		(property "Value" ""
			(at 0 0 90)
			(layer "F.Fab")
			(effects
				(font
					(size 1.27 1.27)
				)
			)
		)
		(duplicate_pad_numbers_are_jumpers no)
		(fp_line
			(start 0.7874 -0.4064)
			(end 0.7874 0.4064)
			(stroke
				(width 0.1524)
				(type default)
			)
			(layer "F.SilkS")
		)
		(fp_line
			(start -0.7874 -0.4064)
			(end 0.7874 -0.4064)
			(stroke
				(width 0.1524)
				(type default)
			)
			(layer "F.SilkS")
		)
		(fp_line
			(start 0.7874 0.4064)
			(end -0.7874 0.4064)
			(stroke
				(width 0.1524)
				(type default)
			)
			(layer "F.SilkS")
		)
		(fp_line
			(start -0.7874 0.4064)
			(end -0.7874 -0.4064)
			(stroke
				(width 0.1524)
				(type default)
			)
			(layer "F.SilkS")
		)
		(fp_line
			(start -0.12065 -0.305054)
			(end -0.12065 -0.2794)
			(stroke
				(width 0.1)
				(type default)
			)
			(layer "F.Fab")
		)
		(fp_line
			(start -0.67945 -0.305054)
			(end -0.12065 -0.305054)
			(stroke
				(width 0.1)
				(type default)
			)
			(layer "F.Fab")
		)
		(fp_line
			(start 0.67945 -0.3048)
			(end 0.67945 0.3048)
			(stroke
				(width 0.1)
				(type default)
			)
			(layer "F.Fab")
		)
		(fp_line
			(start 0.12065 -0.3048)
			(end 0.67945 -0.3048)
			(stroke
				(width 0.1)
				(type default)
			)
			(layer "F.Fab")
		)
		(fp_line
			(start 0.12065 -0.2794)
			(end 0.12065 -0.3048)
			(stroke
				(width 0.1)
				(type default)
			)
			(layer "F.Fab")
		)
		(fp_line
			(start -0.12065 -0.2794)
			(end 0.12065 -0.2794)
			(stroke
				(width 0.1)
				(type default)
			)
			(layer "F.Fab")
		)
		(fp_line
			(start 0.120396 0.2794)
			(end -0.12065 0.2794)
			(stroke
				(width 0.1)
				(type default)
			)
			(layer "F.Fab")
		)
		(fp_line
			(start -0.12065 0.2794)
			(end -0.12065 0.3048)
			(stroke
				(width 0.1)
				(type default)
			)
			(layer "F.Fab")
		)
		(fp_line
			(start 0.67945 0.3048)
			(end 0.120396 0.3048)
			(stroke
				(width 0.1)
				(type default)
			)
			(layer "F.Fab")
		)
		(fp_line
			(start 0.120396 0.3048)
			(end 0.120396 0.2794)
			(stroke
				(width 0.1)
				(type default)
			)
			(layer "F.Fab")
		)
		(fp_line
			(start -0.12065 0.3048)
			(end -0.67945 0.3048)
			(stroke
				(width 0.1)
				(type default)
			)
			(layer "F.Fab")
		)
		(fp_line
			(start -0.67945 0.3048)
			(end -0.67945 -0.305054)
			(stroke
				(width 0.1)
				(type default)
			)
			(layer "F.Fab")
		)
		(pad "1" smd circle
			(at -0.40005 0 90)
			(size 0 0)
			(layers "F.Cu" "F.Mask" "F.Paste")
			(net "SW_P1V8_PCH_AUX_BST")
		)
		(pad "2" smd circle
			(at 0.40005 0 90)
			(size 0 0)
			(layers "F.Cu" "F.Mask" "F.Paste")
			(net "SW_P1V8_PCH_AUX_SW")
		)
	)
)
